(kicad_pcb
	(version 20260206)
	(generator "pcbnew")
	(generator_version "10.0")
	(general
		(thickness 1.6)
		(legacy_teardrops no)
	)
	(paper "A4")
	(title_block
		(title "Bryce Canyon_SCC_16316-1_OCP.brd")
		(comment 1 "Bryce Canyon / footprints 1399-1406 of 1561")
	)
	(layers
		(0 "F.Cu" signal "TOP")
		(4 "In1.Cu" signal "L2GND")
		(6 "In2.Cu" signal "L3")
		(8 "In3.Cu" signal "L4VCC")
		(10 "In4.Cu" signal "L5VCC")
		(12 "In5.Cu" signal "L6")
		(14 "In6.Cu" signal "L7GND")
		(2 "B.Cu" signal "BOTTOM")
		(9 "F.Adhes" user "F.Adhesive")
		(11 "B.Adhes" user "B.Adhesive")
		(13 "F.Paste" user "Package Geometry/Pastemask Top")
		(15 "B.Paste" user "Package Geometry/Pastemask Bottom")
		(5 "F.SilkS" user "Ref Des/Silkscreen Top")
		(7 "B.SilkS" user "Ref Des/Silkscreen Bottom")
		(1 "F.Mask" user "Board Geometry/Soldermask Top")
		(3 "B.Mask" user "Board Geometry/Soldermask Bottom")
		(17 "Dwgs.User" user "User.Drawings")
		(19 "Cmts.User" user "User.Comments")
		(21 "Eco1.User" user "User.Eco1")
		(23 "Eco2.User" user "User.Eco2")
		(25 "Edge.Cuts" user "Board Geometry/Outline")
		(27 "Margin" user)
		(31 "F.CrtYd" user "Package Geometry/Place Bound Top")
		(29 "B.CrtYd" user "Package Geometry/Place Bound Bottom")
		(35 "F.Fab" user "Ref Des/Assembly Top")
		(33 "B.Fab" user "Ref Des/Assembly Bottom")
	)
	(footprint ""
		(layer "B.Cu")
		(at 183.822848 -117.696234 90)
		(property "Reference" "Q35"
			(at 0 0 90)
			(layer "B.SilkS")
			(hide yes)
			(effects
				(font
					(size 1.27 1.27)
				)
				(justify mirror)
			)
		)
		(property "Value" "FDS8878-G-GP"
			(at 3.707384 -1.5367 90)
			(unlocked yes)
			(layer "B.Fab")
			(hide yes)
			(effects
				(font
					(size 1.016 1.016)
					(thickness 0.1524)
				)
				(justify mirror)
			)
		)
		(property "Device Type" "SOIC8H69"
			(at 3.707384 -3.0607 90)
			(unlocked yes)
			(layer "B.Fab")
			(hide yes)
			(effects
				(font
					(size 1.016 1.016)
					(thickness 0.1524)
				)
				(justify mirror)
			)
		)
		(duplicate_pad_numbers_are_jumpers no)
		(fp_line
			(start 2.7432 -1.4224)
			(end 2.7432 1.4224)
			(stroke
				(width 0.1524)
				(type default)
			)
			(layer "B.SilkS")
		)
		(fp_line
			(start -2.1336 -1.4224)
			(end 2.7432 -1.4224)
			(stroke
				(width 0.1524)
				(type default)
			)
			(layer "B.SilkS")
		)
		(fp_line
			(start 2.7178 -0.508)
			(end 2.1844 -0.0508)
			(stroke
				(width 0.1524)
				(type default)
			)
			(layer "B.SilkS")
		)
		(fp_line
			(start 2.1844 -0.0508)
			(end 2.7178 0.508)
			(stroke
				(width 0.1524)
				(type default)
			)
			(layer "B.SilkS")
		)
		(fp_line
			(start 2.7432 1.4224)
			(end 2.6416 1.4224)
			(stroke
				(width 0.1524)
				(type default)
			)
			(layer "B.SilkS")
		)
		(fp_line
			(start 2.7432 1.4224)
			(end -2.1336 1.4224)
			(stroke
				(width 0.1524)
				(type default)
			)
			(layer "B.SilkS")
		)
		(fp_line
			(start -2.1336 1.4224)
			(end -2.1336 -1.4224)
			(stroke
				(width 0.1524)
				(type default)
			)
			(layer "B.SilkS")
		)
		(fp_line
			(start 2.6289 3.4417)
			(end 2.6289 1.4732)
			(stroke
				(width 0.381)
				(type default)
			)
			(layer "B.SilkS")
		)
		(fp_poly
			(pts
				(xy 2.2098 -1.4224) (xy 2.2098 1.4224) (xy -2.2098 1.4224) (xy -2.2098 -1.4224)
			)
			(stroke
				(width 0)
				(type default)
			)
			(fill yes)
			(layer "B.SilkS")
		)
		(fp_rect
			(start 2.450084 2.999994)
			(end -2.450084 -2.999994)
			(stroke
				(width 0)
				(type default)
			)
			(fill no)
			(layer "B.CrtYd")
		)
		(fp_poly
			(pts
				(xy 2.8194 3.6322) (xy 2.8194 -3.6322) (xy -2.8194 -3.6322) (xy -2.8194 1.18364) (xy -2.450084 1.18364)
				(xy -2.450084 -2.999994) (xy 2.450084 -2.999994) (xy 2.450084 2.999994) (xy -2.450084 2.999994)
				(xy -2.450084 1.18618) (xy -2.8194 1.18618) (xy -2.8194 3.6322)
			)
			(stroke
				(width 0)
				(type default)
			)
			(fill no)
			(layer "B.CrtYd")
		)
		(fp_rect
			(start 2.8194 3.6322)
			(end -2.8194 -3.6322)
			(stroke
				(width 0)
				(type default)
			)
			(fill no)
			(layer "B.Fab")
		)
		(pad "1" smd rect
			(at 1.905 2.54 270)
			(size 0.635 1.651)
			(layers "B.Cu" "B.Mask" "B.Paste")
			(net "P1V8_C")
		)
		(pad "2" smd rect
			(at 0.635 2.54 270)
			(size 0.635 1.651)
			(layers "B.Cu" "B.Mask" "B.Paste")
			(net "P1V8_C")
		)
		(pad "3" smd rect
			(at -0.635 2.54 270)
			(size 0.635 1.651)
			(layers "B.Cu" "B.Mask" "B.Paste")
			(net "P1V8_C")
		)
		(pad "4" smd rect
			(at -1.905 2.54 270)
			(size 0.635 1.651)
			(layers "B.Cu" "B.Mask" "B.Paste")
			(net "P1V8_C_G_PG")
		)
		(pad "5" smd rect
			(at -1.905 -2.54 270)
			(size 0.635 1.651)
			(layers "B.Cu" "B.Mask" "B.Paste")
			(net "P1V8_E_OUT")
		)
		(pad "6" smd rect
			(at -0.635 -2.54 270)
			(size 0.635 1.651)
			(layers "B.Cu" "B.Mask" "B.Paste")
			(net "P1V8_E_OUT")
		)
		(pad "7" smd rect
			(at 0.635 -2.54 270)
			(size 0.635 1.651)
			(layers "B.Cu" "B.Mask" "B.Paste")
			(net "P1V8_E_OUT")
		)
		(pad "8" smd rect
			(at 1.905 -2.54 270)
			(size 0.635 1.651)
			(layers "B.Cu" "B.Mask" "B.Paste")
			(net "P1V8_E_OUT")
		)
	)
	(footprint ""
		(layer "B.Cu")
		(at 113.284 -64.4779)
		(property "Reference" "C159"
			(at 0 0 0)
			(layer "B.SilkS")
			(hide yes)
			(effects
				(font
					(size 1.27 1.27)
				)
				(justify mirror)
			)
		)
		(property "Value" "SCD1U6D3V1KX-GP"
			(at 2.8321 -1.7399 0)
			(unlocked yes)
			(layer "B.Fab")
			(hide yes)
			(effects
				(font
					(size 1.016 1.016)
					(thickness 0.1524)
				)
				(justify mirror)
			)
		)
		(property "Device Type" "C0201H13"
			(at 2.8321 -3.2639 0)
			(unlocked yes)
			(layer "B.Fab")
			(hide yes)
			(effects
				(font
					(size 1.016 1.016)
					(thickness 0.1524)
				)
				(justify mirror)
			)
		)
		(duplicate_pad_numbers_are_jumpers no)
		(fp_rect
			(start 0.2794 0.6477)
			(end -0.2794 -0.6477)
			(stroke
				(width 0)
				(type default)
			)
			(fill no)
			(layer "B.CrtYd")
		)
		(fp_rect
			(start 0.2794 0.6477)
			(end -0.2794 -0.6477)
			(stroke
				(width 0)
				(type default)
			)
			(fill no)
			(layer "B.Fab")
		)
		(pad "1" smd custom
			(at 0 -0.2794 180)
			(size 0.0762 0.0762)
			(layers "B.Cu" "B.Mask" "B.Paste")
			(net "P0V9")
			(options
				(clearance outline)
				(anchor circle)
			)
			(primitives
				(gr_poly
					(pts
						(arc
							(start 0.1524 0.127)
							(mid 0.137521 0.162921)
							(end 0.1016 0.1778)
						)
						(arc
							(start -0.1016 0.1778)
							(mid -0.137521 0.162921)
							(end -0.1524 0.127)
						)
						(arc
							(start -0.1524 -0.127)
							(mid -0.137521 -0.162921)
							(end -0.1016 -0.1778)
						)
						(arc
							(start 0.1016 -0.1778)
							(mid 0.137521 -0.162921)
							(end 0.1524 -0.127)
						)
					)
					(width 0)
					(fill yes)
				)
			)
		)
		(pad "2" smd custom
			(at 0 0.2794 180)
			(size 0.0762 0.0762)
			(layers "B.Cu" "B.Mask" "B.Paste")
			(net "GND")
			(options
				(clearance outline)
				(anchor circle)
			)
			(primitives
				(gr_poly
					(pts
						(arc
							(start 0.1524 0.127)
							(mid 0.137521 0.162921)
							(end 0.1016 0.1778)
						)
						(arc
							(start -0.1016 0.1778)
							(mid -0.137521 0.162921)
							(end -0.1524 0.127)
						)
						(arc
							(start -0.1524 -0.127)
							(mid -0.137521 -0.162921)
							(end -0.1016 -0.1778)
						)
						(arc
							(start 0.1016 -0.1778)
							(mid 0.137521 -0.162921)
							(end 0.1524 -0.127)
						)
					)
					(width 0)
					(fill yes)
				)
			)
		)
	)
	(footprint ""
		(layer "B.Cu")
		(at 127.970788 -57.4929 -90)
		(property "Reference" "C257"
			(at 0 0 90)
			(layer "B.SilkS")
			(hide yes)
			(effects
				(font
					(size 1.27 1.27)
				)
				(justify mirror)
			)
		)
		(property "Value" "SC1U6D3V1MX-GP"
			(at -1.9177 2.0193 270)
			(unlocked yes)
			(layer "B.Fab")
			(hide yes)
			(effects
				(font
					(size 1.016 1.016)
					(thickness 0.1524)
				)
				(justify mirror)
			)
		)
		(property "Device Type" "C0201H14"
			(at -1.9177 0.4953 270)
			(unlocked yes)
			(layer "B.Fab")
			(hide yes)
			(effects
				(font
					(size 1.016 1.016)
					(thickness 0.1524)
				)
				(justify mirror)
			)
		)
		(duplicate_pad_numbers_are_jumpers no)
		(fp_rect
			(start 0.1524 0.3048)
			(end -0.1524 -0.3048)
			(stroke
				(width 0)
				(type default)
			)
			(fill no)
			(layer "B.CrtYd")
		)
		(fp_poly
			(pts
				(xy 0.2794 0.6477) (xy 0.2794 -0.6477) (xy -0.2794 -0.6477) (xy -0.2794 -0.1905) (xy -0.1524 -0.1905)
				(xy -0.1524 -0.3048) (xy 0.1524 -0.3048) (xy 0.1524 0.3048) (xy -0.1524 0.3048) (xy -0.1524 -0.1778)
				(xy -0.2794 -0.1778) (xy -0.2794 0.6477)
			)
			(stroke
				(width 0)
				(type default)
			)
			(fill no)
			(layer "B.CrtYd")
		)
		(fp_rect
			(start 0.2794 0.6477)
			(end -0.2794 -0.6477)
			(stroke
				(width 0)
				(type default)
			)
			(fill no)
			(layer "B.Fab")
		)
		(pad "1" smd custom
			(at 0 -0.2794 90)
			(size 0.0762 0.0762)
			(layers "B.Cu" "B.Mask" "B.Paste")
			(net "GB_VDDA")
			(options
				(clearance outline)
				(anchor circle)
			)
			(primitives
				(gr_poly
					(pts
						(arc
							(start 0.1524 0.127)
							(mid 0.137521 0.162921)
							(end 0.1016 0.1778)
						)
						(arc
							(start -0.1016 0.1778)
							(mid -0.137521 0.162921)
							(end -0.1524 0.127)
						)
						(arc
							(start -0.1524 -0.127)
							(mid -0.137521 -0.162921)
							(end -0.1016 -0.1778)
						)
						(arc
							(start 0.1016 -0.1778)
							(mid 0.137521 -0.162921)
							(end 0.1524 -0.127)
						)
					)
					(width 0)
					(fill yes)
				)
			)
		)
		(pad "2" smd custom
			(at 0 0.2794 90)
			(size 0.0762 0.0762)
			(layers "B.Cu" "B.Mask" "B.Paste")
			(net "GND")
			(options
				(clearance outline)
				(anchor circle)
			)
			(primitives
				(gr_poly
					(pts
						(arc
							(start 0.1524 0.127)
							(mid 0.137521 0.162921)
							(end 0.1016 0.1778)
						)
						(arc
							(start -0.1016 0.1778)
							(mid -0.137521 0.162921)
							(end -0.1524 0.127)
						)
						(arc
							(start -0.1524 -0.127)
							(mid -0.137521 -0.162921)
							(end -0.1016 -0.1778)
						)
						(arc
							(start 0.1016 -0.1778)
							(mid 0.137521 -0.162921)
							(end 0.1524 -0.127)
						)
					)
					(width 0)
					(fill yes)
				)
			)
		)
	)
	(footprint ""
		(layer "B.Cu")
		(at 62.1792 -60.579 -90)
		(property "Reference" "C614"
			(at 0 0 90)
			(layer "B.SilkS")
			(hide yes)
			(effects
				(font
					(size 1.27 1.27)
				)
				(justify mirror)
			)
		)
		(property "Value" "SC10U6D3V5KX-4GP"
			(at 0.0762 -6.1214 270)
			(unlocked yes)
			(layer "B.Fab")
			(hide yes)
			(effects
				(font
					(size 1.016 1.016)
					(thickness 0.1524)
				)
				(justify mirror)
			)
		)
		(property "Device Type" "C805H58"
			(at 0.0762 -8.1534 270)
			(unlocked yes)
			(layer "B.Fab")
			(hide yes)
			(effects
				(font
					(size 1.016 1.016)
					(thickness 0.1524)
				)
				(justify mirror)
			)
		)
		(duplicate_pad_numbers_are_jumpers no)
		(fp_line
			(start -0.635 0)
			(end 0.635 0)
			(stroke
				(width 0.508)
				(type default)
			)
			(layer "B.SilkS")
		)
		(fp_rect
			(start 0.9652 1.778)
			(end -0.9652 -1.778)
			(stroke
				(width 0)
				(type default)
			)
			(fill no)
			(layer "B.CrtYd")
		)
		(fp_poly
			(pts
				(xy 0.9652 -1.778) (xy -0.9652 -1.778) (xy -0.9652 1.778) (xy 0.9652 1.778)
			)
			(stroke
				(width 0)
				(type default)
			)
			(fill no)
			(layer "B.Fab")
		)
		(pad "1" smd rect
			(at 0 -0.9652 90)
			(size 1.397 1.143)
			(layers "B.Cu" "B.Mask" "B.Paste")
			(net "P0V9")
		)
		(pad "2" smd rect
			(at 0 0.9652 90)
			(size 1.397 1.143)
			(layers "B.Cu" "B.Mask" "B.Paste")
			(net "GND")
		)
	)
	(footprint ""
		(layer "B.Cu")
		(at 122.474228 -66.72453 -90)
		(property "Reference" "C230"
			(at 0 0 90)
			(layer "B.SilkS")
			(hide yes)
			(effects
				(font
					(size 1.27 1.27)
				)
				(justify mirror)
			)
		)
		(property "Value" "SCD1U6D3V1KX-GP"
			(at 2.8321 -1.7399 270)
			(unlocked yes)
			(layer "B.Fab")
			(hide yes)
			(effects
				(font
					(size 1.016 1.016)
					(thickness 0.1524)
				)
				(justify mirror)
			)
		)
		(property "Device Type" "C0201H13"
			(at 2.8321 -3.2639 270)
			(unlocked yes)
			(layer "B.Fab")
			(hide yes)
			(effects
				(font
					(size 1.016 1.016)
					(thickness 0.1524)
				)
				(justify mirror)
			)
		)
		(duplicate_pad_numbers_are_jumpers no)
		(fp_rect
			(start 0.2794 0.6477)
			(end -0.2794 -0.6477)
			(stroke
				(width 0)
				(type default)
			)
			(fill no)
			(layer "B.CrtYd")
		)
		(fp_rect
			(start 0.2794 0.6477)
			(end -0.2794 -0.6477)
			(stroke
				(width 0)
				(type default)
			)
			(fill no)
			(layer "B.Fab")
		)
		(pad "1" smd custom
			(at 0 -0.2794 90)
			(size 0.0762 0.0762)
			(layers "B.Cu" "B.Mask" "B.Paste")
			(net "GB_VDDA")
			(options
				(clearance outline)
				(anchor circle)
			)
			(primitives
				(gr_poly
					(pts
						(arc
							(start 0.1524 0.127)
							(mid 0.137521 0.162921)
							(end 0.1016 0.1778)
						)
						(arc
							(start -0.1016 0.1778)
							(mid -0.137521 0.162921)
							(end -0.1524 0.127)
						)
						(arc
							(start -0.1524 -0.127)
							(mid -0.137521 -0.162921)
							(end -0.1016 -0.1778)
						)
						(arc
							(start 0.1016 -0.1778)
							(mid 0.137521 -0.162921)
							(end 0.1524 -0.127)
						)
					)
					(width 0)
					(fill yes)
				)
			)
		)
		(pad "2" smd custom
			(at 0 0.2794 90)
			(size 0.0762 0.0762)
			(layers "B.Cu" "B.Mask" "B.Paste")
			(net "GND")
			(options
				(clearance outline)
				(anchor circle)
			)
			(primitives
				(gr_poly
					(pts
						(arc
							(start 0.1524 0.127)
							(mid 0.137521 0.162921)
							(end 0.1016 0.1778)
						)
						(arc
							(start -0.1016 0.1778)
							(mid -0.137521 0.162921)
							(end -0.1524 0.127)
						)
						(arc
							(start -0.1524 -0.127)
							(mid -0.137521 -0.162921)
							(end -0.1016 -0.1778)
						)
						(arc
							(start 0.1016 -0.1778)
							(mid 0.137521 -0.162921)
							(end 0.1524 -0.127)
						)
					)
					(width 0)
					(fill yes)
				)
			)
		)
	)
	(footprint ""
		(layer "B.Cu")
		(at 96.363282 -79.98333 90)
		(property "Reference" "R310"
			(at 0 0 90)
			(layer "B.SilkS")
			(hide yes)
			(effects
				(font
					(size 1.27 1.27)
				)
				(justify mirror)
			)
		)
		(property "Value" "10KR2F-2-GP"
			(at -0.064008 -3.993896 90)
			(unlocked yes)
			(layer "B.Fab")
			(hide yes)
			(effects
				(font
					(size 1.016 1.016)
					(thickness 0.1524)
				)
				(justify mirror)
			)
		)
		(property "Device Type" "R402H16"
			(at -0.064008 -5.517896 90)
			(unlocked yes)
			(layer "B.Fab")
			(hide yes)
			(effects
				(font
					(size 1.016 1.016)
					(thickness 0.1524)
				)
				(justify mirror)
			)
		)
		(duplicate_pad_numbers_are_jumpers no)
		(fp_line
			(start 0.508 -0.9398)
			(end 0.508 0.9398)
			(stroke
				(width 0.1524)
				(type default)
			)
			(layer "B.SilkS")
		)
		(fp_line
			(start -0.508 -0.9398)
			(end 0.508 -0.9398)
			(stroke
				(width 0.1524)
				(type default)
			)
			(layer "B.SilkS")
		)
		(fp_rect
			(start 0.508 0.9398)
			(end -0.508 -0.9398)
			(stroke
				(width 0)
				(type default)
			)
			(fill no)
			(layer "B.CrtYd")
		)
		(fp_rect
			(start 0.508 0.9398)
			(end -0.508 -0.9398)
			(stroke
				(width 0)
				(type default)
			)
			(fill no)
			(layer "B.Fab")
		)
		(pad "1" smd custom
			(at 0 -0.4445 270)
			(size 0.1397 0.1397)
			(layers "B.Cu" "B.Mask" "B.Paste")
			(net "P1V8_E")
			(options
				(clearance outline)
				(anchor circle)
			)
			(primitives
				(gr_poly
					(pts
						(arc
							(start -0.1778 0.2794)
							(mid -0.249642 0.249642)
							(end -0.2794 0.1778)
						)
						(arc
							(start -0.2794 -0.1778)
							(mid -0.249642 -0.249642)
							(end -0.1778 -0.2794)
						)
						(arc
							(start 0.1778 -0.2794)
							(mid 0.249642 -0.249642)
							(end 0.2794 -0.1778)
						)
						(arc
							(start 0.2794 0.1778)
							(mid 0.249642 0.249642)
							(end 0.1778 0.2794)
						)
					)
					(width 0)
					(fill yes)
				)
			)
		)
		(pad "2" smd custom
			(at 0 0.4445 270)
			(size 0.1397 0.1397)
			(layers "B.Cu" "B.Mask" "B.Paste")
			(net "FW_RESET_N")
			(options
				(clearance outline)
				(anchor circle)
			)
			(primitives
				(gr_poly
					(pts
						(arc
							(start -0.1778 0.2794)
							(mid -0.249642 0.249642)
							(end -0.2794 0.1778)
						)
						(arc
							(start -0.2794 -0.1778)
							(mid -0.249642 -0.249642)
							(end -0.1778 -0.2794)
						)
						(arc
							(start 0.1778 -0.2794)
							(mid 0.249642 -0.249642)
							(end 0.2794 -0.1778)
						)
						(arc
							(start 0.2794 0.1778)
							(mid 0.249642 0.249642)
							(end 0.1778 0.2794)
						)
					)
					(width 0)
					(fill yes)
				)
			)
		)
	)
	(footprint ""
		(layer "B.Cu")
		(at 170.636438 -45.197014 -90)
		(property "Reference" "C410"
			(at 0 0 90)
			(layer "B.SilkS")
			(hide yes)
			(effects
				(font
					(size 1.27 1.27)
				)
				(justify mirror)
			)
		)
		(property "Value" "SC10U6D3V5KX-4GP"
			(at 0.0762 -6.1214 270)
			(unlocked yes)
			(layer "B.Fab")
			(hide yes)
			(effects
				(font
					(size 1.016 1.016)
					(thickness 0.1524)
				)
				(justify mirror)
			)
		)
		(property "Device Type" "C805H58"
			(at 0.0762 -8.1534 270)
			(unlocked yes)
			(layer "B.Fab")
			(hide yes)
			(effects
				(font
					(size 1.016 1.016)
					(thickness 0.1524)
				)
				(justify mirror)
			)
		)
		(duplicate_pad_numbers_are_jumpers no)
		(fp_line
			(start -0.635 0)
			(end 0.635 0)
			(stroke
				(width 0.508)
				(type default)
			)
			(layer "B.SilkS")
		)
		(fp_rect
			(start 0.9652 1.778)
			(end -0.9652 -1.778)
			(stroke
				(width 0)
				(type default)
			)
			(fill no)
			(layer "B.CrtYd")
		)
		(fp_poly
			(pts
				(xy 0.9652 -1.778) (xy -0.9652 -1.778) (xy -0.9652 1.778) (xy 0.9652 1.778)
			)
			(stroke
				(width 0)
				(type default)
			)
			(fill no)
			(layer "B.Fab")
		)
		(pad "1" smd rect
			(at 0 -0.9652 90)
			(size 1.397 1.143)
			(layers "B.Cu" "B.Mask" "B.Paste")
			(net "P0V975")
		)
		(pad "2" smd rect
			(at 0 0.9652 90)
			(size 1.397 1.143)
			(layers "B.Cu" "B.Mask" "B.Paste")
			(net "GND")
		)
	)
	(footprint ""
		(layer "B.Cu")
		(at 121.5136 -72.263)
		(property "Reference" "C125"
			(at 0 0 0)
			(layer "B.SilkS")
			(hide yes)
			(effects
				(font
					(size 1.27 1.27)
				)
				(justify mirror)
			)
		)
		(property "Value" "SC1KP25V1KX-GP"
			(at 2.8321 -1.7399 0)
			(unlocked yes)
			(layer "B.Fab")
			(hide yes)
			(effects
				(font
					(size 1.016 1.016)
					(thickness 0.1524)
				)
				(justify mirror)
			)
		)
		(property "Device Type" "C0201H13"
			(at 2.8321 -3.2639 0)
			(unlocked yes)
			(layer "B.Fab")
			(hide yes)
			(effects
				(font
					(size 1.016 1.016)
					(thickness 0.1524)
				)
				(justify mirror)
			)
		)
		(duplicate_pad_numbers_are_jumpers no)
		(fp_rect
			(start 0.2794 0.6477)
			(end -0.2794 -0.6477)
			(stroke
				(width 0)
				(type default)
			)
			(fill no)
			(layer "B.CrtYd")
		)
		(fp_rect
			(start 0.2794 0.6477)
			(end -0.2794 -0.6477)
			(stroke
				(width 0)
				(type default)
			)
			(fill no)
			(layer "B.Fab")
		)
		(pad "1" smd custom
			(at 0 -0.2794 180)
			(size 0.0762 0.0762)
			(layers "B.Cu" "B.Mask" "B.Paste")
			(net "P1V8_E")
			(options
				(clearance outline)
				(anchor circle)
			)
			(primitives
				(gr_poly
					(pts
						(arc
							(start 0.1524 0.127)
							(mid 0.137521 0.162921)
							(end 0.1016 0.1778)
						)
						(arc
							(start -0.1016 0.1778)
							(mid -0.137521 0.162921)
							(end -0.1524 0.127)
						)
						(arc
							(start -0.1524 -0.127)
							(mid -0.137521 -0.162921)
							(end -0.1016 -0.1778)
						)
						(arc
							(start 0.1016 -0.1778)
							(mid 0.137521 -0.162921)
							(end 0.1524 -0.127)
						)
					)
					(width 0)
					(fill yes)
				)
			)
		)
		(pad "2" smd custom
			(at 0 0.2794 180)
			(size 0.0762 0.0762)
			(layers "B.Cu" "B.Mask" "B.Paste")
			(net "GND")
			(options
				(clearance outline)
				(anchor circle)
			)
			(primitives
				(gr_poly
					(pts
						(arc
							(start 0.1524 0.127)
							(mid 0.137521 0.162921)
							(end 0.1016 0.1778)
						)
						(arc
							(start -0.1016 0.1778)
							(mid -0.137521 0.162921)
							(end -0.1524 0.127)
						)
						(arc
							(start -0.1524 -0.127)
							(mid -0.137521 -0.162921)
							(end -0.1016 -0.1778)
						)
						(arc
							(start 0.1016 -0.1778)
							(mid 0.137521 -0.162921)
							(end 0.1524 -0.127)
						)
					)
					(width 0)
					(fill yes)
				)
			)
		)
	)
)
